(kicad_pcb
	(version 20260206)
	(generator "pcbnew")
	(generator_version "10.0")
	(general
		(thickness 1.6)
		(legacy_teardrops no)
	)
	(paper "A4")
	(title_block
		(title "timecard-production-celestica-r4006 — R4006-B0001-02_R01.brd")
		(comment 1 "Time Appliance Project (Time Card) / footprints 164-168 of 1113")
	)
	(layers
		(0 "F.Cu" signal "TOP")
		(4 "In1.Cu" signal "L02_GND1")
		(6 "In2.Cu" signal "L03_SIG1")
		(8 "In3.Cu" signal "L04_GND2")
		(10 "In4.Cu" signal "L05_VCC1")
		(12 "In5.Cu" signal "L06_VCC2")
		(14 "In6.Cu" signal "L07_GND3")
		(16 "In7.Cu" signal "L08_SIG2")
		(18 "In8.Cu" signal "L09_GND4")
		(2 "B.Cu" signal "BOTTOM")
		(9 "F.Adhes" user "F.Adhesive")
		(11 "B.Adhes" user "B.Adhesive")
		(13 "F.Paste" user "Package Geometry/Pastemask Top")
		(15 "B.Paste" user "Package Geometry/Pastemask Bottom")
		(5 "F.SilkS" user "Ref Des/Silkscreen Top")
		(7 "B.SilkS" user "Ref Des/Silkscreen Bottom")
		(1 "F.Mask" user "Board Geometry/Soldermask Top")
		(3 "B.Mask" user "Board Geometry/Soldermask Bottom")
		(17 "Dwgs.User" user "User.Drawings")
		(19 "Cmts.User" user "User.Comments")
		(21 "Eco1.User" user "User.Eco1")
		(23 "Eco2.User" user "User.Eco2")
		(25 "Edge.Cuts" user "Board Geometry/Outline")
		(27 "Margin" user)
		(31 "F.CrtYd" user "Package Geometry/Place Bound Top")
		(29 "B.CrtYd" user "Package Geometry/Place Bound Bottom")
		(35 "F.Fab" user "Ref Des/Assembly Top")
		(33 "B.Fab" user "Ref Des/Assembly Bottom")
	)
	(footprint ""
		(layer "F.Cu")
		(at 102.5398 -64.2874 -90)
		(property "Reference" "R292"
			(at 2.8194 -0.75057 90)
			(unlocked yes)
			(layer "F.SilkS")
			(effects
				(font
					(size 0.7874 0.5842)
					(thickness 0.1524)
				)
			)
		)
		(property "Value" "VAL*"
			(at 0.02032 2.13233 270)
			(unlocked yes)
			(layer "F.Fab")
			(hide yes)
			(effects
				(font
					(size 0.7874 0.5842)
					(thickness 0.1524)
				)
			)
		)
		(property "Tolerance" "TOL*"
			(at 0.044704 3.05435 270)
			(unlocked yes)
			(layer "Cmts.User")
			(hide yes)
			(effects
				(font
					(size 0.7874 0.5842)
					(thickness 0.1524)
				)
			)
		)
		(property "User Part Number" "PARTNUM*"
			(at 0.02032 4.024884 270)
			(unlocked yes)
			(layer "Cmts.User")
			(hide yes)
			(effects
				(font
					(size 0.7874 0.5842)
					(thickness 0.1524)
				)
			)
		)
		(property "Device Type" "RESISTOR-G155-11002-01,10KOHM,A"
			(at 0.008382 1.210564 270)
			(unlocked yes)
			(layer "F.Fab")
			(hide yes)
			(effects
				(font
					(size 0.7874 0.5842)
					(thickness 0.1524)
				)
			)
		)
		(duplicate_pad_numbers_are_jumpers no)
		(fp_line
			(start -1.143 0.5588)
			(end 1.143 0.5588)
			(stroke
				(width 0.1)
				(type default)
			)
			(layer "F.SilkS")
		)
		(fp_line
			(start 1.143 0.5588)
			(end 1.143 -0.5588)
			(stroke
				(width 0.1)
				(type default)
			)
			(layer "F.SilkS")
		)
		(fp_line
			(start -1.143 -0.5588)
			(end -1.143 0.5588)
			(stroke
				(width 0.1)
				(type default)
			)
			(layer "F.SilkS")
		)
		(fp_line
			(start 1.143 -0.5588)
			(end -1.143 -0.5588)
			(stroke
				(width 0.1)
				(type default)
			)
			(layer "F.SilkS")
		)
		(fp_rect
			(start 1.143 0.5588)
			(end -1.143 -0.5588)
			(stroke
				(width 0)
				(type default)
			)
			(fill no)
			(layer "F.CrtYd")
		)
		(fp_line
			(start -0.508 0.3048)
			(end 0.508 0.3048)
			(stroke
				(width 0.1)
				(type default)
			)
			(layer "F.Fab")
		)
		(fp_line
			(start 0.508 0.3048)
			(end 0.508 -0.3048)
			(stroke
				(width 0.1)
				(type default)
			)
			(layer "F.Fab")
		)
		(fp_line
			(start -0.508 -0.3048)
			(end -0.508 0.3048)
			(stroke
				(width 0.1)
				(type default)
			)
			(layer "F.Fab")
		)
		(fp_line
			(start 0.508 -0.3048)
			(end -0.508 -0.3048)
			(stroke
				(width 0.1)
				(type default)
			)
			(layer "F.Fab")
		)
		(pad "1" smd rect
			(at -0.5334 0 270)
			(size 0.7112 0.6096)
			(layers "F.Cu" "F.Mask" "F.Paste")
			(net "XP3R3V_FPGA")
		)
		(pad "2" smd rect
			(at 0.5334 0 270)
			(size 0.7112 0.6096)
			(layers "F.Cu" "F.Mask" "F.Paste")
			(net "FPGA_IO_4")
		)
		(zone
			(layer "F.Cu")
			(hatch none 0.5)
			(connect_pads
				(clearance 0)
			)
			(min_thickness 0.25)
			(keepout
				(tracks allowed)
				(vias not_allowed)
				(pads allowed)
				(copperpour not_allowed)
				(footprints allowed)
			)
			(placement
				(enabled no)
				(sheetname "")
			)
			(fill
				(thermal_gap 0.5)
				(thermal_bridge_width 0.5)
				(island_removal_mode 0)
			)
			(polygon
				(pts
					(xy 102.235 -64.2112) (xy 102.8446 -64.2112) (xy 102.8446 -64.3636) (xy 102.235 -64.3636)
				)
			)
		)
	)
	(footprint ""
		(layer "F.Cu")
		(at 55.1942 -74.9808 90)
		(property "Reference" "R418"
			(at -0.5588 4.28117 90)
			(unlocked yes)
			(layer "F.SilkS")
			(effects
				(font
					(size 0.7874 0.5842)
					(thickness 0.1524)
				)
			)
		)
		(property "Value" "VAL*"
			(at 0.02032 2.13233 90)
			(unlocked yes)
			(layer "F.Fab")
			(hide yes)
			(effects
				(font
					(size 0.7874 0.5842)
					(thickness 0.1524)
				)
			)
		)
		(property "Device Type" "RESISTOR-G155-14701-01,4.7KOHMA"
			(at 0.008382 1.210564 90)
			(unlocked yes)
			(layer "F.Fab")
			(hide yes)
			(effects
				(font
					(size 0.7874 0.5842)
					(thickness 0.1524)
				)
			)
		)
		(property "User Part Number" "PARTNUM*"
			(at 0.02032 4.024884 90)
			(unlocked yes)
			(layer "Cmts.User")
			(hide yes)
			(effects
				(font
					(size 0.7874 0.5842)
					(thickness 0.1524)
				)
			)
		)
		(property "Tolerance" "TOL*"
			(at 0.044704 3.05435 90)
			(unlocked yes)
			(layer "Cmts.User")
			(hide yes)
			(effects
				(font
					(size 0.7874 0.5842)
					(thickness 0.1524)
				)
			)
		)
		(duplicate_pad_numbers_are_jumpers no)
		(fp_line
			(start 1.143 -0.5588)
			(end -1.143 -0.5588)
			(stroke
				(width 0.1)
				(type default)
			)
			(layer "F.SilkS")
		)
		(fp_line
			(start -1.143 -0.5588)
			(end -1.143 0.5588)
			(stroke
				(width 0.1)
				(type default)
			)
			(layer "F.SilkS")
		)
		(fp_line
			(start 1.143 0.5588)
			(end 1.143 -0.5588)
			(stroke
				(width 0.1)
				(type default)
			)
			(layer "F.SilkS")
		)
		(fp_line
			(start -1.143 0.5588)
			(end 1.143 0.5588)
			(stroke
				(width 0.1)
				(type default)
			)
			(layer "F.SilkS")
		)
		(fp_rect
			(start -1.143 0.5588)
			(end 1.143 -0.5588)
			(stroke
				(width 0)
				(type default)
			)
			(fill no)
			(layer "F.CrtYd")
		)
		(fp_line
			(start 0.508 -0.3048)
			(end -0.508 -0.3048)
			(stroke
				(width 0.1)
				(type default)
			)
			(layer "F.Fab")
		)
		(fp_line
			(start -0.508 -0.3048)
			(end -0.508 0.3048)
			(stroke
				(width 0.1)
				(type default)
			)
			(layer "F.Fab")
		)
		(fp_line
			(start 0.508 0.3048)
			(end 0.508 -0.3048)
			(stroke
				(width 0.1)
				(type default)
			)
			(layer "F.Fab")
		)
		(fp_line
			(start -0.508 0.3048)
			(end 0.508 0.3048)
			(stroke
				(width 0.1)
				(type default)
			)
			(layer "F.Fab")
		)
		(pad "1" smd rect
			(at -0.5334 0 90)
			(size 0.7112 0.6096)
			(layers "F.Cu" "F.Mask" "F.Paste")
			(net "XP3R3V_FPGA")
		)
		(pad "2" smd rect
			(at 0.5334 0 90)
			(size 0.7112 0.6096)
			(layers "F.Cu" "F.Mask" "F.Paste")
			(net "UNNAMED_6_LM75BDPTSSOP8_I59_A0")
		)
		(zone
			(layer "F.Cu")
			(hatch none 0.5)
			(connect_pads
				(clearance 0)
			)
			(min_thickness 0.25)
			(keepout
				(tracks not_allowed)
				(vias allowed)
				(pads allowed)
				(copperpour not_allowed)
				(footprints allowed)
			)
			(placement
				(enabled no)
				(sheetname "")
			)
			(fill
				(thermal_gap 0.5)
				(thermal_bridge_width 0.5)
				(island_removal_mode 0)
			)
			(polygon
				(pts
					(xy 55.499 -74.9046) (xy 55.499 -75.057) (xy 54.8894 -75.057) (xy 54.8894 -74.9046)
				)
			)
		)
		(zone
			(layer "F.Cu")
			(hatch none 0.5)
			(connect_pads
				(clearance 0)
			)
			(min_thickness 0.25)
			(keepout
				(tracks allowed)
				(vias not_allowed)
				(pads allowed)
				(copperpour not_allowed)
				(footprints allowed)
			)
			(placement
				(enabled no)
				(sheetname "")
			)
			(fill
				(thermal_gap 0.5)
				(thermal_bridge_width 0.5)
				(island_removal_mode 0)
			)
			(polygon
				(pts
					(xy 55.499 -74.9046) (xy 55.499 -75.057) (xy 54.8894 -75.057) (xy 54.8894 -74.9046)
				)
			)
		)
	)
	(footprint ""
		(layer "F.Cu")
		(at 142.24 -59.563 90)
		(property "Reference" "C259"
			(at 3.048 -1.86563 90)
			(unlocked yes)
			(layer "F.SilkS")
			(effects
				(font
					(size 0.7874 0.5842)
					(thickness 0.1524)
				)
			)
		)
		(property "Value" "VAL*"
			(at 0.0762 2.067306 90)
			(unlocked yes)
			(layer "F.Fab")
			(hide yes)
			(effects
				(font
					(size 0.7874 0.5842)
					(thickness 0.1524)
				)
			)
		)
		(property "Device Type" "CAPACITOR-G105-0B223-EK,0.022UA"
			(at 0.0508 1.127506 90)
			(unlocked yes)
			(layer "F.Fab")
			(hide yes)
			(effects
				(font
					(size 0.7874 0.5842)
					(thickness 0.1524)
				)
			)
		)
		(property "User Part Number" "PARTNUM*"
			(at 0.1016 4.023106 90)
			(unlocked yes)
			(layer "Cmts.User")
			(hide yes)
			(effects
				(font
					(size 0.7874 0.5842)
					(thickness 0.1524)
				)
			)
		)
		(property "Tolerance" "TOL*"
			(at 0.0762 3.032506 90)
			(unlocked yes)
			(layer "Cmts.User")
			(hide yes)
			(effects
				(font
					(size 0.7874 0.5842)
					(thickness 0.1524)
				)
			)
		)
		(duplicate_pad_numbers_are_jumpers no)
		(fp_line
			(start 1.143 -0.5588)
			(end -1.143 -0.5588)
			(stroke
				(width 0.1)
				(type default)
			)
			(layer "F.SilkS")
		)
		(fp_line
			(start -1.143 -0.5588)
			(end -1.143 0.5588)
			(stroke
				(width 0.1)
				(type default)
			)
			(layer "F.SilkS")
		)
		(fp_line
			(start 1.143 0.5588)
			(end 1.143 -0.5588)
			(stroke
				(width 0.1)
				(type default)
			)
			(layer "F.SilkS")
		)
		(fp_line
			(start -1.143 0.5588)
			(end 1.143 0.5588)
			(stroke
				(width 0.1)
				(type default)
			)
			(layer "F.SilkS")
		)
		(fp_rect
			(start -1.143 -0.5588)
			(end 1.143 0.5588)
			(stroke
				(width 0)
				(type default)
			)
			(fill no)
			(layer "F.CrtYd")
		)
		(fp_line
			(start 0.508 -0.3048)
			(end -0.508 -0.3048)
			(stroke
				(width 0.1)
				(type default)
			)
			(layer "F.Fab")
		)
		(fp_line
			(start -0.508 -0.3048)
			(end -0.508 0.3048)
			(stroke
				(width 0.1)
				(type default)
			)
			(layer "F.Fab")
		)
		(fp_line
			(start 0.508 0.3048)
			(end 0.508 -0.3048)
			(stroke
				(width 0.1)
				(type default)
			)
			(layer "F.Fab")
		)
		(fp_line
			(start -0.508 0.3048)
			(end 0.508 0.3048)
			(stroke
				(width 0.1)
				(type default)
			)
			(layer "F.Fab")
		)
		(pad "1" smd rect
			(at -0.5334 0 90)
			(size 0.7112 0.6096)
			(layers "F.Cu" "F.Mask" "F.Paste")
			(net "XP1R0V_SS")
		)
		(pad "2" smd rect
			(at 0.5334 0 90)
			(size 0.7112 0.6096)
			(layers "F.Cu" "F.Mask" "F.Paste")
			(net "XP1R0V_AGND")
		)
		(zone
			(layer "F.Cu")
			(hatch none 0.5)
			(connect_pads
				(clearance 0)
			)
			(min_thickness 0.25)
			(keepout
				(tracks allowed)
				(vias not_allowed)
				(pads allowed)
				(copperpour not_allowed)
				(footprints allowed)
			)
			(placement
				(enabled no)
				(sheetname "")
			)
			(fill
				(thermal_gap 0.5)
				(thermal_bridge_width 0.5)
				(island_removal_mode 0)
			)
			(polygon
				(pts
					(xy 141.9352 -59.4868) (xy 142.5448 -59.4868) (xy 142.5448 -59.6392) (xy 141.9352 -59.6392)
				)
			)
		)
	)
	(footprint ""
		(layer "F.Cu")
		(at 79.756 -48.133)
		(property "Reference" "R97"
			(at 0.127 14.26337 0)
			(unlocked yes)
			(layer "F.SilkS")
			(effects
				(font
					(size 0.7874 0.5842)
					(thickness 0.1524)
				)
			)
		)
		(property "Value" "VAL*"
			(at 0.02032 2.13233 0)
			(unlocked yes)
			(layer "F.Fab")
			(hide yes)
			(effects
				(font
					(size 0.7874 0.5842)
					(thickness 0.1524)
				)
			)
		)
		(property "Device Type" "RESISTOR-G155-100R0-J0,0OHM,-"
			(at 0.008382 1.210564 0)
			(unlocked yes)
			(layer "F.Fab")
			(hide yes)
			(effects
				(font
					(size 0.7874 0.5842)
					(thickness 0.1524)
				)
			)
		)
		(property "User Part Number" "PARTNUM*"
			(at 0.02032 4.024884 0)
			(unlocked yes)
			(layer "Cmts.User")
			(hide yes)
			(effects
				(font
					(size 0.7874 0.5842)
					(thickness 0.1524)
				)
			)
		)
		(property "Tolerance" "TOL*"
			(at 0.044704 3.05435 0)
			(unlocked yes)
			(layer "Cmts.User")
			(hide yes)
			(effects
				(font
					(size 0.7874 0.5842)
					(thickness 0.1524)
				)
			)
		)
		(duplicate_pad_numbers_are_jumpers no)
		(fp_line
			(start -1.143 -0.5588)
			(end -1.143 0.5588)
			(stroke
				(width 0.1)
				(type default)
			)
			(layer "F.SilkS")
		)
		(fp_line
			(start -1.143 0.5588)
			(end 1.143 0.5588)
			(stroke
				(width 0.1)
				(type default)
			)
			(layer "F.SilkS")
		)
		(fp_line
			(start 1.143 -0.5588)
			(end -1.143 -0.5588)
			(stroke
				(width 0.1)
				(type default)
			)
			(layer "F.SilkS")
		)
		(fp_line
			(start 1.143 0.5588)
			(end 1.143 -0.5588)
			(stroke
				(width 0.1)
				(type default)
			)
			(layer "F.SilkS")
		)
		(fp_rect
			(start -1.143 0.5588)
			(end 1.143 -0.5588)
			(stroke
				(width 0)
				(type default)
			)
			(fill no)
			(layer "F.CrtYd")
		)
		(fp_line
			(start -0.508 -0.3048)
			(end -0.508 0.3048)
			(stroke
				(width 0.1)
				(type default)
			)
			(layer "F.Fab")
		)
		(fp_line
			(start -0.508 0.3048)
			(end 0.508 0.3048)
			(stroke
				(width 0.1)
				(type default)
			)
			(layer "F.Fab")
		)
		(fp_line
			(start 0.508 -0.3048)
			(end -0.508 -0.3048)
			(stroke
				(width 0.1)
				(type default)
			)
			(layer "F.Fab")
		)
		(fp_line
			(start 0.508 0.3048)
			(end 0.508 -0.3048)
			(stroke
				(width 0.1)
				(type default)
			)
			(layer "F.Fab")
		)
		(pad "1" smd rect
			(at -0.5334 0)
			(size 0.7112 0.6096)
			(layers "F.Cu" "F.Mask" "F.Paste")
			(net "R_MAC_USB_DP")
		)
		(pad "2" smd rect
			(at 0.5334 0)
			(size 0.7112 0.6096)
			(layers "F.Cu" "F.Mask" "F.Paste")
			(net "MUX_USB_DP")
		)
		(zone
			(layer "F.Cu")
			(hatch none 0.5)
			(connect_pads
				(clearance 0)
			)
			(min_thickness 0.25)
			(keepout
				(tracks allowed)
				(vias not_allowed)
				(pads allowed)
				(copperpour not_allowed)
				(footprints allowed)
			)
			(placement
				(enabled no)
				(sheetname "")
			)
			(fill
				(thermal_gap 0.5)
				(thermal_bridge_width 0.5)
				(island_removal_mode 0)
			)
			(polygon
				(pts
					(xy 79.6798 -47.8282) (xy 79.8322 -47.8282) (xy 79.8322 -48.4378) (xy 79.6798 -48.4378)
				)
			)
		)
	)
	(footprint ""
		(layer "F.Cu")
		(at 19.468338 -50.165 180)
		(property "Reference" "R401"
			(at -2.883662 0.21463 0)
			(unlocked yes)
			(layer "F.SilkS")
			(effects
				(font
					(size 0.7874 0.5842)
					(thickness 0.1524)
				)
			)
		)
		(property "Value" "VAL*"
			(at 0.02032 2.13233 180)
			(unlocked yes)
			(layer "F.Fab")
			(hide yes)
			(effects
				(font
					(size 0.7874 0.5842)
					(thickness 0.1524)
				)
			)
		)
		(property "Device Type" "RESISTOR-G155-11000-01,100OHM,A"
			(at 0.008382 1.210564 180)
			(unlocked yes)
			(layer "F.Fab")
			(hide yes)
			(effects
				(font
					(size 0.7874 0.5842)
					(thickness 0.1524)
				)
			)
		)
		(property "User Part Number" "PARTNUM*"
			(at 0.02032 4.024884 180)
			(unlocked yes)
			(layer "Cmts.User")
			(hide yes)
			(effects
				(font
					(size 0.7874 0.5842)
					(thickness 0.1524)
				)
			)
		)
		(property "Tolerance" "TOL*"
			(at 0.044704 3.05435 180)
			(unlocked yes)
			(layer "Cmts.User")
			(hide yes)
			(effects
				(font
					(size 0.7874 0.5842)
					(thickness 0.1524)
				)
			)
		)
		(duplicate_pad_numbers_are_jumpers no)
		(fp_line
			(start 1.143 0.5588)
			(end 1.143 -0.5588)
			(stroke
				(width 0.1)
				(type default)
			)
			(layer "F.SilkS")
		)
		(fp_line
			(start 1.143 -0.5588)
			(end -1.143 -0.5588)
			(stroke
				(width 0.1)
				(type default)
			)
			(layer "F.SilkS")
		)
		(fp_line
			(start -1.143 0.5588)
			(end 1.143 0.5588)
			(stroke
				(width 0.1)
				(type default)
			)
			(layer "F.SilkS")
		)
		(fp_line
			(start -1.143 -0.5588)
			(end -1.143 0.5588)
			(stroke
				(width 0.1)
				(type default)
			)
			(layer "F.SilkS")
		)
		(fp_poly
			(pts
				(xy -1.143 0.5588) (xy 1.143 0.5588) (xy 1.143 -0.5588) (xy -1.143 -0.5588)
			)
			(stroke
				(width 0)
				(type default)
			)
			(fill no)
			(layer "F.CrtYd")
		)
		(fp_line
			(start 0.508 0.3048)
			(end 0.508 -0.3048)
			(stroke
				(width 0.1)
				(type default)
			)
			(layer "F.Fab")
		)
		(fp_line
			(start 0.508 -0.3048)
			(end -0.508 -0.3048)
			(stroke
				(width 0.1)
				(type default)
			)
			(layer "F.Fab")
		)
		(fp_line
			(start -0.508 0.3048)
			(end 0.508 0.3048)
			(stroke
				(width 0.1)
				(type default)
			)
			(layer "F.Fab")
		)
		(fp_line
			(start -0.508 -0.3048)
			(end -0.508 0.3048)
			(stroke
				(width 0.1)
				(type default)
			)
			(layer "F.Fab")
		)
		(pad "1" smd rect
			(at -0.5334 0 180)
			(size 0.7112 0.6096)
			(layers "F.Cu" "F.Mask" "F.Paste")
			(net "FPGA_OUT_SMA4_LED_GREEN_N")
		)
		(pad "2" smd rect
			(at 0.5334 0 180)
			(size 0.7112 0.6096)
			(layers "F.Cu" "F.Mask" "F.Paste")
			(net "UNNAMED_14_LED4PV14_I268_4")
		)
		(zone
			(layer "F.Cu")
			(hatch none 0.5)
			(connect_pads
				(clearance 0)
			)
			(min_thickness 0.25)
			(keepout
				(tracks allowed)
				(vias not_allowed)
				(pads allowed)
				(copperpour not_allowed)
				(footprints allowed)
			)
			(placement
				(enabled no)
				(sheetname "")
			)
			(fill
				(thermal_gap 0.5)
				(thermal_bridge_width 0.5)
				(island_removal_mode 0)
			)
			(polygon
				(pts
					(xy 19.544538 -50.4698) (xy 19.392138 -50.4698) (xy 19.392138 -49.8602) (xy 19.544538 -49.8602)
				)
			)
		)
		(zone
			(layer "F.Cu")
			(hatch none 0.5)
			(connect_pads
				(clearance 0)
			)
			(min_thickness 0.25)
			(keepout
				(tracks not_allowed)
				(vias allowed)
				(pads allowed)
				(copperpour not_allowed)
				(footprints allowed)
			)
			(placement
				(enabled no)
				(sheetname "")
			)
			(fill
				(thermal_gap 0.5)
				(thermal_bridge_width 0.5)
				(island_removal_mode 0)
			)
			(polygon
				(pts
					(xy 19.544538 -50.4698) (xy 19.392138 -50.4698) (xy 19.392138 -49.8602) (xy 19.544538 -49.8602)
				)
			)
		)
	)
)
